# S9S_MB_2U (Grand Teton) — schematic netlist excerpt (pin names and nets, part order shuffled) for the footprints in the layout excerpt that follows; sources: Cadence DE-HDL packaged netlist, KiCad conversion of 03242023_DA0F0TMBIJ0_F0T_Motherboard_J_brd_V01_OCP.brd

U241  74LVC2G08DP  IC  pkg TSSOP8_0-65_3X3  page 165
  \1a\  = OCP_V3_2_PRSNT0_R_N
  \1b\  = OCP_V3_2_PRSNT1_R_N
  \2y\  = OCP_V3_2_PRSNT23_R_N
  GND  = GND
  \2a\  = OCP_V3_2_PRSNT2_R_N
  \2b\  = OCP_V3_2_PRSNT3_R_N
  \1y\  = OCP_V3_2_PRSNT01_R_N
  VCC  = P3V3_AUX

C1045  Q_CAP  22UF 4V 20% X6S  pkg C0402  page 74 : A = PVCCIN_CPU0 ; B = GND

(kicad_pcb
	(version 20260206)
	(generator "pcbnew")
	(generator_version "10.0")
	(general
		(thickness 1.6)
		(legacy_teardrops no)
	)
	(paper "A4")
	(title_block
		(title "03242023_DA0F0TMBIJ0_F0T_Motherboard_J_brd_V01_OCP.brd")
		(comment 1 "Grand Teton / footprints 3892-3893 of 6105")
	)
	(layers
		(0 "F.Cu" signal "TOP")
		(4 "In1.Cu" signal "GND")
		(6 "In2.Cu" signal "IN1")
		(8 "In3.Cu" signal "GND1")
		(10 "In4.Cu" signal "IN2")
		(12 "In5.Cu" signal "GND2")
		(14 "In6.Cu" signal "IN3")
		(16 "In7.Cu" signal "GND3")
		(18 "In8.Cu" signal "VCC")
		(20 "In9.Cu" signal "VCC1")
		(22 "In10.Cu" signal "GND4")
		(24 "In11.Cu" signal "IN4")
		(26 "In12.Cu" signal "GND5")
		(28 "In13.Cu" signal "IN5")
		(30 "In14.Cu" signal "GND6")
		(32 "In15.Cu" signal "IN6")
		(34 "In16.Cu" signal "GND7")
		(2 "B.Cu" signal "BOTTOM")
		(9 "F.Adhes" user "F.Adhesive")
		(11 "B.Adhes" user "B.Adhesive")
		(13 "F.Paste" user "Package Geometry/Pastemask Top")
		(15 "B.Paste" user "Package Geometry/Pastemask Bottom")
		(5 "F.SilkS" user "Ref Des/Silkscreen Top")
		(7 "B.SilkS" user "Ref Des/Silkscreen Bottom")
		(1 "F.Mask" user "Board Geometry/Soldermask Top")
		(3 "B.Mask" user "Board Geometry/Soldermask Bottom")
		(17 "Dwgs.User" user "User.Drawings")
		(19 "Cmts.User" user "User.Comments")
		(21 "Eco1.User" user "User.Eco1")
		(23 "Eco2.User" user "User.Eco2")
		(25 "Edge.Cuts" user "Board Geometry/Outline")
		(27 "Margin" user)
		(31 "F.CrtYd" user "Package Geometry/Place Bound Top")
		(29 "B.CrtYd" user "Package Geometry/Place Bound Bottom")
		(35 "F.Fab" user "Ref Des/Assembly Top")
		(33 "B.Fab" user "Ref Des/Assembly Bottom")
	)
	(footprint ""
		(layer "F.Cu")
		(at 365.46663 -240.276888 90)
		(property "Reference" "C1045"
			(at 0 0 90)
			(layer "F.SilkS")
			(hide yes)
			(effects
				(font
					(size 1.27 1.27)
				)
			)
		)
		(property "Value" ""
			(at 0 0 90)
			(layer "F.Fab")
			(effects
				(font
					(size 1.27 1.27)
				)
			)
		)
		(duplicate_pad_numbers_are_jumpers no)
		(fp_line
			(start 0.7874 -0.4064)
			(end 0.7874 0.4064)
			(stroke
				(width 0.1524)
				(type default)
			)
			(layer "F.SilkS")
		)
		(fp_line
			(start -0.7874 -0.4064)
			(end 0.7874 -0.4064)
			(stroke
				(width 0.1524)
				(type default)
			)
			(layer "F.SilkS")
		)
		(fp_line
			(start 0.7874 0.4064)
			(end -0.7874 0.4064)
			(stroke
				(width 0.1524)
				(type default)
			)
			(layer "F.SilkS")
		)
		(fp_line
			(start -0.7874 0.4064)
			(end -0.7874 -0.4064)
			(stroke
				(width 0.1524)
				(type default)
			)
			(layer "F.SilkS")
		)
		(fp_line
			(start -0.12065 -0.305054)
			(end -0.12065 -0.2794)
			(stroke
				(width 0.1)
				(type default)
			)
			(layer "F.Fab")
		)
		(fp_line
			(start -0.67945 -0.305054)
			(end -0.12065 -0.305054)
			(stroke
				(width 0.1)
				(type default)
			)
			(layer "F.Fab")
		)
		(fp_line
			(start 0.67945 -0.3048)
			(end 0.67945 0.3048)
			(stroke
				(width 0.1)
				(type default)
			)
			(layer "F.Fab")
		)
		(fp_line
			(start 0.12065 -0.3048)
			(end 0.67945 -0.3048)
			(stroke
				(width 0.1)
				(type default)
			)
			(layer "F.Fab")
		)
		(fp_line
			(start 0.12065 -0.2794)
			(end 0.12065 -0.3048)
			(stroke
				(width 0.1)
				(type default)
			)
			(layer "F.Fab")
		)
		(fp_line
			(start -0.12065 -0.2794)
			(end 0.12065 -0.2794)
			(stroke
				(width 0.1)
				(type default)
			)
			(layer "F.Fab")
		)
		(fp_line
			(start 0.120396 0.2794)
			(end -0.12065 0.2794)
			(stroke
				(width 0.1)
				(type default)
			)
			(layer "F.Fab")
		)
		(fp_line
			(start -0.12065 0.2794)
			(end -0.12065 0.3048)
			(stroke
				(width 0.1)
				(type default)
			)
			(layer "F.Fab")
		)
		(fp_line
			(start 0.67945 0.3048)
			(end 0.120396 0.3048)
			(stroke
				(width 0.1)
				(type default)
			)
			(layer "F.Fab")
		)
		(fp_line
			(start 0.120396 0.3048)
			(end 0.120396 0.2794)
			(stroke
				(width 0.1)
				(type default)
			)
			(layer "F.Fab")
		)
		(fp_line
			(start -0.12065 0.3048)
			(end -0.67945 0.3048)
			(stroke
				(width 0.1)
				(type default)
			)
			(layer "F.Fab")
		)
		(fp_line
			(start -0.67945 0.3048)
			(end -0.67945 -0.305054)
			(stroke
				(width 0.1)
				(type default)
			)
			(layer "F.Fab")
		)
		(pad "1" smd circle
			(at -0.40005 0 90)
			(size 0 0)
			(layers "F.Cu" "F.Mask" "F.Paste")
			(net "PVCCIN_CPU0")
		)
		(pad "2" smd circle
			(at 0.40005 0 90)
			(size 0 0)
			(layers "F.Cu" "F.Mask" "F.Paste")
			(net "GND")
		)
	)
	(footprint ""
		(layer "F.Cu")
		(at 5.35432 -74.719688)
		(property "Reference" "U241"
			(at -1.23698 2.420112 0)
			(unlocked yes)
			(layer "F.SilkS")
			(effects
				(font
					(size 0.7874 0.5842)
					(thickness 0.1524)
				)
				(justify left)
			)
		)
		(property "Value" ""
			(at 0 0 0)
			(layer "F.Fab")
			(effects
				(font
					(size 1.27 1.27)
				)
			)
		)
		(duplicate_pad_numbers_are_jumpers no)
		(fp_line
			(start -1.207008 -1.549908)
			(end -1.207008 1.549908)
			(stroke
				(width 0.1524)
				(type default)
			)
			(layer "F.SilkS")
		)
		(fp_line
			(start -1.207008 1.549908)
			(end 1.207008 1.549908)
			(stroke
				(width 0.1524)
				(type default)
			)
			(layer "F.SilkS")
		)
		(fp_line
			(start -0.762508 -1.549908)
			(end -1.207008 -1.549908)
			(stroke
				(width 0.1524)
				(type default)
			)
			(layer "F.SilkS")
		)
		(fp_line
			(start 0 -0.635)
			(end -0.762508 -1.549908)
			(stroke
				(width 0.1524)
				(type default)
			)
			(layer "F.SilkS")
		)
		(fp_line
			(start 0.762508 -1.549908)
			(end 0 -0.635)
			(stroke
				(width 0.1524)
				(type default)
			)
			(layer "F.SilkS")
		)
		(fp_line
			(start 1.207008 -1.549908)
			(end 0.762508 -1.549908)
			(stroke
				(width 0.1524)
				(type default)
			)
			(layer "F.SilkS")
		)
		(fp_line
			(start 1.207008 1.549908)
			(end 1.207008 -1.549908)
			(stroke
				(width 0.1524)
				(type default)
			)
			(layer "F.SilkS")
		)
		(fp_poly
			(pts
				(xy -3.48996 -1.64211) (xy -2.47396 -1.13411) (xy -3.48996 -0.62611)
			)
			(stroke
				(width 0)
				(type default)
			)
			(fill yes)
			(layer "F.SilkS")
		)
		(fp_line
			(start -1.549908 -1.549908)
			(end -1.549908 1.549908)
			(stroke
				(width 0.1)
				(type default)
			)
			(layer "F.Fab")
		)
		(fp_line
			(start -1.549908 1.549908)
			(end 1.549908 1.549908)
			(stroke
				(width 0.1)
				(type default)
			)
			(layer "F.Fab")
		)
		(fp_line
			(start 1.549908 -1.549908)
			(end -1.549908 -1.549908)
			(stroke
				(width 0.1)
				(type default)
			)
			(layer "F.Fab")
		)
		(fp_line
			(start 1.549908 1.549908)
			(end 1.549908 -1.549908)
			(stroke
				(width 0.1)
				(type default)
			)
			(layer "F.Fab")
		)
		(fp_poly
			(pts
				(xy -3.4036 -1.53289) (xy -3.4036 -0.51689) (xy -2.3876 -1.02489)
			)
			(stroke
				(width 0)
				(type default)
			)
			(fill yes)
			(layer "F.Fab")
		)
		(pad "1" smd rect
			(at -1.774952 -1.02489 270)
			(size 0.508 0.8636)
			(layers "F.Cu" "F.Mask" "F.Paste")
			(net "OCP_V3_2_PRSNT0_R_N")
		)
		(pad "2" smd rect
			(at -1.774952 -0.32512 270)
			(size 0.4064 0.8636)
			(layers "F.Cu" "F.Mask" "F.Paste")
			(net "OCP_V3_2_PRSNT1_R_N")
		)
		(pad "3" smd rect
			(at -1.774952 0.32512 270)
			(size 0.4064 0.8636)
			(layers "F.Cu" "F.Mask" "F.Paste")
			(net "OCP_V3_2_PRSNT23_R_N")
		)
		(pad "4" smd rect
			(at -1.774952 1.02489 270)
			(size 0.508 0.8636)
			(layers "F.Cu" "F.Mask" "F.Paste")
			(net "GND")
		)
		(pad "5" smd rect
			(at 1.774952 1.02489 270)
			(size 0.508 0.8636)
			(layers "F.Cu" "F.Mask" "F.Paste")
			(net "OCP_V3_2_PRSNT2_R_N")
		)
		(pad "6" smd rect
			(at 1.774952 0.32512 270)
			(size 0.4064 0.8636)
			(layers "F.Cu" "F.Mask" "F.Paste")
			(net "OCP_V3_2_PRSNT3_R_N")
		)
		(pad "7" smd rect
			(at 1.774952 -0.32512 270)
			(size 0.4064 0.8636)
			(layers "F.Cu" "F.Mask" "F.Paste")
			(net "OCP_V3_2_PRSNT01_R_N")
		)
		(pad "8" smd rect
			(at 1.774952 -1.02489 270)
			(size 0.508 0.8636)
			(layers "F.Cu" "F.Mask" "F.Paste")
			(net "P3V3_AUX")
		)
	)
)
